(kicad_pcb
	(version 20241229)
	(generator "pcbnew")
	(generator_version "9.0")
	(general
		(thickness 1.711)
		(legacy_teardrops no)
	)
	(paper "A4")
	(title_block
		(title "Antmicro Baseboard for Jetson AGX Thor")
		(date "2026-02-18")
		(rev "1.1.0")
		(company "Antmicro Ltd")
		(comment 1 "www.antmicro.com")
		(comment 9 "footprints 1027-1029 of 1170")
	)
	(layers
		(0 "F.Cu" signal)
		(4 "In1.Cu" signal)
		(6 "In2.Cu" signal)
		(8 "In3.Cu" signal)
		(10 "In4.Cu" jumper)
		(12 "In5.Cu" signal)
		(14 "In6.Cu" signal)
		(16 "In7.Cu" signal)
		(18 "In8.Cu" signal)
		(2 "B.Cu" signal)
		(9 "F.Adhes" user "F.Adhesive")
		(11 "B.Adhes" user "B.Adhesive")
		(13 "F.Paste" user)
		(15 "B.Paste" user)
		(5 "F.SilkS" user "F.Silkscreen")
		(7 "B.SilkS" user "B.Silkscreen")
		(1 "F.Mask" user)
		(3 "B.Mask" user)
		(17 "Dwgs.User" user "User.Drawings")
		(19 "Cmts.User" user "User.Comments")
		(21 "Eco1.User" user "User.Eco1")
		(23 "Eco2.User" user "User.Eco2")
		(25 "Edge.Cuts" user)
		(27 "Margin" user)
		(31 "F.CrtYd" user "F.Courtyard")
		(29 "B.CrtYd" user "B.Courtyard")
		(35 "F.Fab" user)
		(33 "B.Fab" user)
	)
	(footprint "antmicro-footprints:SOD-523"
		(layer "B.Cu")
		(at 230.069 116.6 180)
		(property "Reference" "D45"
			(at 0.999 -0.4 0)
			(layer "B.SilkS")
			(effects
				(font
					(size 0.7 0.7)
					(thickness 0.15)
				)
				(justify left bottom mirror)
			)
		)
		(property "Value" "PESD5Z5.0F"
			(at 0 -1.499 0)
			(layer "B.Fab")
			(effects
				(font
					(size 0.7 0.7)
					(thickness 0.15)
				)
				(justify left bottom mirror)
			)
		)
		(property "Datasheet" "https://assets.nexperia.com/documents/data-sheet/PESD5Z5_0.pdf"
			(at 0 0 0)
			(layer "B.Fab")
			(hide yes)
			(effects
				(font
					(size 1.27 1.27)
					(thickness 0.15)
				)
				(justify mirror)
			)
		)
		(property "Description" "Unidirectional TVS, 30 kV,  SOD-523, 5 V, 89 pF"
			(at 0 0 0)
			(layer "B.Fab")
			(hide yes)
			(effects
				(font
					(size 1.27 1.27)
					(thickness 0.15)
				)
				(justify mirror)
			)
		)
		(property "Manufacturer" "Nexperia"
			(at 0 0 180)
			(unlocked yes)
			(layer "B.Fab")
			(hide yes)
			(effects
				(font
					(size 1 1)
					(thickness 0.15)
				)
				(justify mirror)
			)
		)
		(property "MPN" "PESD5Z5.0F"
			(at 0 0 180)
			(unlocked yes)
			(layer "B.Fab")
			(hide yes)
			(effects
				(font
					(size 1 1)
					(thickness 0.15)
				)
				(justify mirror)
			)
		)
		(property "Author" "Antmicro"
			(at 0 0 180)
			(unlocked yes)
			(layer "B.Fab")
			(hide yes)
			(effects
				(font
					(size 1 1)
					(thickness 0.15)
				)
				(justify mirror)
			)
		)
		(property "License" "Apache-2.0"
			(at 0 0 180)
			(unlocked yes)
			(layer "B.Fab")
			(hide yes)
			(effects
				(font
					(size 1 1)
					(thickness 0.15)
				)
				(justify mirror)
			)
		)
		(sheetname "/USB Hub/")
		(sheetfile "usb_hub.kicad_sch")
		(attr smd)
		(fp_line
			(start -0.35 0.5)
			(end -0.35 -0.5)
			(stroke
				(width 0.15)
				(type solid)
			)
			(layer "B.SilkS")
		)
		(fp_rect
			(start -1 0.6)
			(end 1 -0.6)
			(stroke
				(width 0.05)
				(type solid)
			)
			(fill no)
			(layer "B.CrtYd")
		)
		(fp_line
			(start 0.65 0.425)
			(end 0.65 -0.423)
			(stroke
				(width 0.15)
				(type solid)
			)
			(layer "B.Fab")
		)
		(fp_line
			(start -0.35 0.4)
			(end -0.35 -0.4)
			(stroke
				(width 0.15)
				(type solid)
			)
			(layer "B.Fab")
		)
		(fp_line
			(start -0.652 0.425)
			(end 0.65 0.425)
			(stroke
				(width 0.15)
				(type solid)
			)
			(layer "B.Fab")
		)
		(fp_line
			(start -0.652 -0.423)
			(end 0.65 -0.423)
			(stroke
				(width 0.15)
				(type solid)
			)
			(layer "B.Fab")
		)
		(fp_line
			(start -0.652 -0.423)
			(end -0.652 0.425)
			(stroke
				(width 0.15)
				(type solid)
			)
			(layer "B.Fab")
		)
		(fp_text user "License: Apache-2.0"
			(at -1.276 -5.9 0)
			(layer "B.Fab")
			(effects
				(font
					(size 0.7 0.7)
					(thickness 0.15)
				)
				(justify left bottom mirror)
			)
		)
		(fp_text user "${REFERENCE}"
			(at -1.276 -3.499 0)
			(layer "B.Fab")
			(effects
				(font
					(size 0.7 0.7)
					(thickness 0.15)
				)
				(justify left bottom mirror)
			)
		)
		(fp_text user "Author: Antmicro"
			(at -1.276 -4.7 0)
			(layer "B.Fab")
			(effects
				(font
					(size 0.7 0.7)
					(thickness 0.15)
				)
				(justify left bottom mirror)
			)
		)
		(pad "1" smd roundrect
			(at -0.701 0 180)
			(size 0.5 0.6)
			(layers "B.Cu" "B.Mask" "B.Paste")
			(roundrect_rratio 0.25)
			(net 71 "/USB Hub/USBC3_VBUS")
			(pinfunction "C")
			(pintype "passive")
		)
		(pad "2" smd roundrect
			(at 0.699 0 180)
			(size 0.5 0.6)
			(layers "B.Cu" "B.Mask" "B.Paste")
			(roundrect_rratio 0.25)
			(net 1 "GND")
			(pinfunction "A")
			(pintype "passive")
		)
	)
	(footprint "antmicro-footprints:Spacer_Drill3.7mm_H8mm_9774080151R"
		(locked yes)
		(layer "B.Cu")
		(at 80.430532 143.71 -90)
		(descr "Spacer M=3 h=8mm fi=5.1mm")
		(property "Reference" "H1"
			(at 0 3.2 90)
			(layer "B.SilkS")
			(effects
				(font
					(size 0.7 0.7)
					(thickness 0.15)
				)
				(justify left bottom mirror)
			)
		)
		(property "Value" "Spacer_Drill3.7mm_H8mm_9774080151R"
			(at 0 -4 90)
			(layer "B.Fab")
			(effects
				(font
					(size 0.7 0.7)
					(thickness 0.15)
				)
				(justify left bottom mirror)
			)
		)
		(property "Datasheet" "https://www.we-online.com/components/products/datasheet/9774080151R.pdf"
			(at 0 0 90)
			(layer "B.Fab")
			(hide yes)
			(effects
				(font
					(size 1.27 1.27)
					(thickness 0.15)
				)
				(justify mirror)
			)
		)
		(property "Description" "Spacer, SMT, Non Stop, Steel, Swage Round, 5.1 mm x 8 mm, M2.5 Thread, WA-SMSI Series"
			(at 0 0 90)
			(layer "B.Fab")
			(hide yes)
			(effects
				(font
					(size 1.27 1.27)
					(thickness 0.15)
				)
				(justify mirror)
			)
		)
		(property "Manufacturer" "Würth Elektronik"
			(at 0 0 270)
			(unlocked yes)
			(layer "B.Fab")
			(hide yes)
			(effects
				(font
					(size 1 1)
					(thickness 0.15)
				)
				(justify mirror)
			)
		)
		(property "MPN" "9774080151R"
			(at 0 0 270)
			(unlocked yes)
			(layer "B.Fab")
			(hide yes)
			(effects
				(font
					(size 1 1)
					(thickness 0.15)
				)
				(justify mirror)
			)
		)
		(property "Author" "Antmicro"
			(at 0 0 270)
			(unlocked yes)
			(layer "B.Fab")
			(hide yes)
			(effects
				(font
					(size 1 1)
					(thickness 0.15)
				)
				(justify mirror)
			)
		)
		(property "License" "Apache-2.0"
			(at 0 0 270)
			(unlocked yes)
			(layer "B.Fab")
			(hide yes)
			(effects
				(font
					(size 1 1)
					(thickness 0.15)
				)
				(justify mirror)
			)
		)
		(sheetname "/")
		(sheetfile "jetson-agx-thor-baseboard.kicad_sch")
		(solder_paste_margin_ratio -1)
		(attr smd)
		(fp_circle
			(center 0 0)
			(end 3.05 0)
			(stroke
				(width 0.05)
				(type solid)
			)
			(fill no)
			(layer "B.CrtYd")
		)
		(fp_circle
			(center 0 0)
			(end 2.6 0)
			(stroke
				(width 0.15)
				(type solid)
			)
			(fill no)
			(layer "B.Fab")
		)
		(fp_text user "License: Apache-2.0"
			(at -9.6 -8.9 90)
			(layer "B.Fab")
			(effects
				(font
					(size 0.7 0.7)
					(thickness 0.15)
				)
				(justify left bottom mirror)
			)
		)
		(fp_text user "${REFERENCE}"
			(at -9.6 -6.5 90)
			(layer "B.Fab")
			(effects
				(font
					(size 0.7 0.7)
					(thickness 0.15)
				)
				(justify left bottom mirror)
			)
		)
		(fp_text user "Author: Antmicro"
			(at -9.6 -7.7 90)
			(layer "B.Fab")
			(effects
				(font
					(size 0.7 0.7)
					(thickness 0.15)
				)
				(justify left bottom mirror)
			)
		)
		(pad "" smd custom
			(at -1.7 -1.7 180)
			(size 0.62 0.62)
			(layers "B.Paste")
			(thermal_bridge_angle 90)
			(options
				(clearance outline)
				(anchor circle)
			)
			(primitives
				(gr_arc
					(start 1.266786 0.24747)
					(mid 0.285453 -0.29439)
					(end -0.250195 -1.279127)
					(width 0.2)
				)
				(gr_arc
					(start 1.259603 0.339191)
					(mid 0.218448 -0.232561)
					(end -0.34334 -1.279127)
					(width 0.2)
				)
				(gr_arc
					(start 1.255279 0.431435)
					(mid 0.152481 -0.169693)
					(end -0.436309 -1.279127)
					(width 0.2)
				)
				(gr_arc
					(start 1.253811 0.524161)
					(mid 0.087542 -0.105784)
					(end -0.529126 -1.279127)
					(width 0.2)
				)
				(gr_arc
					(start 1.275473 0.621136)
					(mid 0.0309 -0.033527)
					(end -0.621807 -1.279127)
					(width 0.2)
				)
				(gr_arc
					(start 1.263664 0.711602)
					(mid -0.037759 0.026651)
					(end -0.71437 -1.279127)
					(width 0.2)
				)
				(gr_arc
					(start 1.253435 0.802342)
					(mid -0.105837 0.087395)
					(end -0.806826 -1.279127)
					(width 0.2)
				)
				(gr_arc
					(start 1.267475 0.897258)
					(mid -0.165236 0.156885)
					(end -0.899187 -1.279127)
					(width 0.2)
				)
				(gr_arc
					(start 1.270645 0.990112)
					(mid -0.228522 0.222449)
					(end -0.991463 -1.279127)
					(width 0.2)
				)
				(gr_arc
					(start 1.266278 1.081674)
					(mid -0.294507 0.285313)
					(end -1.083663 -1.279127)
					(width 0.2)
				)
				(gr_line
					(start 1.279127 0.250195)
					(end 1.279127 1.083663)
					(width 0.2)
				)
				(gr_line
					(start -0.250195 -1.279127)
					(end -1.083663 -1.279127)
					(width 0.2)
				)
			)
		)
		(pad "" smd custom
			(at -1.7 1.7 270)
			(size 0.62 0.62)
			(layers "B.Paste")
			(thermal_bridge_angle 90)
			(options
				(clearance outline)
				(anchor circle)
			)
			(primitives
				(gr_arc
					(start 1.266786 0.24747)
					(mid 0.285453 -0.29439)
					(end -0.250195 -1.279127)
					(width 0.2)
				)
				(gr_arc
					(start 1.259603 0.339191)
					(mid 0.218448 -0.232561)
					(end -0.34334 -1.279127)
					(width 0.2)
				)
				(gr_arc
					(start 1.255279 0.431435)
					(mid 0.152481 -0.169693)
					(end -0.436309 -1.279127)
					(width 0.2)
				)
				(gr_arc
					(start 1.253811 0.524161)
					(mid 0.087542 -0.105784)
					(end -0.529126 -1.279127)
					(width 0.2)
				)
				(gr_arc
					(start 1.275473 0.621136)
					(mid 0.0309 -0.033527)
					(end -0.621807 -1.279127)
					(width 0.2)
				)
				(gr_arc
					(start 1.263664 0.711602)
					(mid -0.037759 0.026651)
					(end -0.71437 -1.279127)
					(width 0.2)
				)
				(gr_arc
					(start 1.253435 0.802342)
					(mid -0.105837 0.087395)
					(end -0.806826 -1.279127)
					(width 0.2)
				)
				(gr_arc
					(start 1.267475 0.897258)
					(mid -0.165236 0.156885)
					(end -0.899187 -1.279127)
					(width 0.2)
				)
				(gr_arc
					(start 1.270645 0.990112)
					(mid -0.228522 0.222449)
					(end -0.991463 -1.279127)
					(width 0.2)
				)
				(gr_arc
					(start 1.266278 1.081674)
					(mid -0.294507 0.285313)
					(end -1.083663 -1.279127)
					(width 0.2)
				)
				(gr_line
					(start 1.279127 0.250195)
					(end 1.279127 1.083663)
					(width 0.2)
				)
				(gr_line
					(start -0.250195 -1.279127)
					(end -1.083663 -1.279127)
					(width 0.2)
				)
			)
		)
		(pad "" smd custom
			(at 1.7 -1.7 90)
			(size 0.62 0.62)
			(layers "B.Paste")
			(thermal_bridge_angle 90)
			(options
				(clearance outline)
				(anchor circle)
			)
			(primitives
				(gr_arc
					(start 1.266786 0.24747)
					(mid 0.285453 -0.29439)
					(end -0.250195 -1.279127)
					(width 0.2)
				)
				(gr_arc
					(start 1.259603 0.339191)
					(mid 0.218448 -0.232561)
					(end -0.34334 -1.279127)
					(width 0.2)
				)
				(gr_arc
					(start 1.255279 0.431435)
					(mid 0.152481 -0.169693)
					(end -0.436309 -1.279127)
					(width 0.2)
				)
				(gr_arc
					(start 1.253811 0.524161)
					(mid 0.087542 -0.105784)
					(end -0.529126 -1.279127)
					(width 0.2)
				)
				(gr_arc
					(start 1.275473 0.621136)
					(mid 0.0309 -0.033527)
					(end -0.621807 -1.279127)
					(width 0.2)
				)
				(gr_arc
					(start 1.263664 0.711602)
					(mid -0.037759 0.026651)
					(end -0.71437 -1.279127)
					(width 0.2)
				)
				(gr_arc
					(start 1.253435 0.802342)
					(mid -0.105837 0.087395)
					(end -0.806826 -1.279127)
					(width 0.2)
				)
				(gr_arc
					(start 1.267475 0.897258)
					(mid -0.165236 0.156885)
					(end -0.899187 -1.279127)
					(width 0.2)
				)
				(gr_arc
					(start 1.270645 0.990112)
					(mid -0.228522 0.222449)
					(end -0.991463 -1.279127)
					(width 0.2)
				)
				(gr_arc
					(start 1.266278 1.081674)
					(mid -0.294507 0.285313)
					(end -1.083663 -1.279127)
					(width 0.2)
				)
				(gr_line
					(start 1.279127 0.250195)
					(end 1.279127 1.083663)
					(width 0.2)
				)
				(gr_line
					(start -0.250195 -1.279127)
					(end -1.083663 -1.279127)
					(width 0.2)
				)
			)
		)
		(pad "" smd custom
			(at 1.7 1.7)
			(size 0.62 0.62)
			(layers "B.Paste")
			(thermal_bridge_angle 90)
			(options
				(clearance outline)
				(anchor circle)
			)
			(primitives
				(gr_arc
					(start 1.266786 0.24747)
					(mid 0.285453 -0.29439)
					(end -0.250195 -1.279127)
					(width 0.2)
				)
				(gr_arc
					(start 1.259603 0.339191)
					(mid 0.218448 -0.232561)
					(end -0.34334 -1.279127)
					(width 0.2)
				)
				(gr_arc
					(start 1.255279 0.431435)
					(mid 0.152481 -0.169693)
					(end -0.436309 -1.279127)
					(width 0.2)
				)
				(gr_arc
					(start 1.253811 0.524161)
					(mid 0.087542 -0.105784)
					(end -0.529126 -1.279127)
					(width 0.2)
				)
				(gr_arc
					(start 1.275473 0.621136)
					(mid 0.0309 -0.033527)
					(end -0.621807 -1.279127)
					(width 0.2)
				)
				(gr_arc
					(start 1.263664 0.711602)
					(mid -0.037759 0.026651)
					(end -0.71437 -1.279127)
					(width 0.2)
				)
				(gr_arc
					(start 1.253435 0.802342)
					(mid -0.105837 0.087395)
					(end -0.806826 -1.279127)
					(width 0.2)
				)
				(gr_arc
					(start 1.267475 0.897258)
					(mid -0.165236 0.156885)
					(end -0.899187 -1.279127)
					(width 0.2)
				)
				(gr_arc
					(start 1.270645 0.990112)
					(mid -0.228522 0.222449)
					(end -0.991463 -1.279127)
					(width 0.2)
				)
				(gr_arc
					(start 1.266278 1.081674)
					(mid -0.294507 0.285313)
					(end -1.083663 -1.279127)
					(width 0.2)
				)
				(gr_line
					(start 1.279127 0.250195)
					(end 1.279127 1.083663)
					(width 0.2)
				)
				(gr_line
					(start -0.250195 -1.279127)
					(end -1.083663 -1.279127)
					(width 0.2)
				)
			)
		)
		(pad "1" thru_hole circle
			(at 0 0 270)
			(size 6 6)
			(drill 3.7)
			(layers "*.Cu" "*.Mask")
			(remove_unused_layers no)
			(net 1 "GND")
			(pintype "passive")
		)
	)
	(footprint "antmicro-footprints:TSOT23-6"
		(layer "B.Cu")
		(at 232.4 134)
		(property "Reference" "U20"
			(at -0.24 -2.58 0)
			(layer "B.SilkS")
			(effects
				(font
					(size 0.7 0.7)
					(thickness 0.15)
				)
				(justify right top mirror)
			)
		)
		(property "Value" "AP22615A_TSOT26"
			(at 0 -2.600001 0)
			(layer "B.Fab")
			(effects
				(font
					(size 0.7 0.7)
					(thickness 0.15)
				)
				(justify right top mirror)
			)
		)
		(property "Datasheet" "https://www.mouser.com/datasheet/2/115/DIOD_S_A0008958405_1-2543193.pdf"
			(at 0 0 0)
			(layer "B.Fab")
			(hide yes)
			(effects
				(font
					(size 1.27 1.27)
					(thickness 0.15)
				)
				(justify mirror)
			)
		)
		(property "Description" "Power Load Distribution Switch, High Side, Active High, 1 Output, 5.5 V, 3.6 A, 0.04 ohm, TSOT-26-6"
			(at 0 0 0)
			(layer "B.Fab")
			(hide yes)
			(effects
				(font
					(size 1.27 1.27)
					(thickness 0.15)
				)
				(justify mirror)
			)
		)
		(property "MPN" "AP22615AWU-7"
			(at 0 0 180)
			(unlocked yes)
			(layer "B.Fab")
			(hide yes)
			(effects
				(font
					(size 1 1)
					(thickness 0.15)
				)
				(justify mirror)
			)
		)
		(property "Manufacturer" "Diodes Incorporated"
			(at 0 0 180)
			(unlocked yes)
			(layer "B.Fab")
			(hide yes)
			(effects
				(font
					(size 1 1)
					(thickness 0.15)
				)
				(justify mirror)
			)
		)
		(property "Author" "Antmicro"
			(at 0 0 180)
			(unlocked yes)
			(layer "B.Fab")
			(hide yes)
			(effects
				(font
					(size 1 1)
					(thickness 0.15)
				)
				(justify mirror)
			)
		)
		(property "License" "Apache-2.0"
			(at 0 0 180)
			(unlocked yes)
			(layer "B.Fab")
			(hide yes)
			(effects
				(font
					(size 1 1)
					(thickness 0.15)
				)
				(justify mirror)
			)
		)
		(sheetname "/USB Hub/")
		(sheetfile "usb_hub.kicad_sch")
		(attr smd)
		(fp_line
			(start -1 -1.55)
			(end -1 -1.4)
			(stroke
				(width 0.15)
				(type solid)
			)
			(layer "B.SilkS")
		)
		(fp_line
			(start -1 1.5)
			(end -1 1.375)
			(stroke
				(width 0.15)
				(type solid)
			)
			(layer "B.SilkS")
		)
		(fp_line
			(start 1 -1.55)
			(end -1 -1.55)
			(stroke
				(width 0.15)
				(type solid)
			)
			(layer "B.SilkS")
		)
		(fp_line
			(start 1 -1.55)
			(end 1 -1.4)
			(stroke
				(width 0.15)
				(type solid)
			)
			(layer "B.SilkS")
		)
		(fp_line
			(start 1 1.497)
			(end -1 1.5)
			(stroke
				(width 0.15)
				(type solid)
			)
			(layer "B.SilkS")
		)
		(fp_line
			(start 1 1.497)
			(end 1 1.375)
			(stroke
				(width 0.15)
				(type solid)
			)
			(layer "B.SilkS")
		)
		(fp_circle
			(center -1.44 1.5)
			(end -1.39 1.5)
			(stroke
				(width 0.15)
				(type solid)
			)
			(fill yes)
			(layer "B.SilkS")
		)
		(fp_poly
			(pts
				(xy 1.930001 1.7) (xy 1.930001 -1.7) (xy -1.930001 -1.7) (xy -1.930001 1.7)
			)
			(stroke
				(width 0.05)
				(type solid)
			)
			(fill no)
			(layer "B.CrtYd")
		)
		(fp_line
			(start -0.45 1.520999)
			(end -0.876001 1.096)
			(stroke
				(width 0.15)
				(type solid)
			)
			(layer "B.Fab")
		)
		(fp_poly
			(pts
				(xy 0.875 -1.528) (xy 0.875 1.525) (xy -0.875 1.525) (xy -0.875 -1.528)
			)
			(stroke
				(width 0.15)
				(type solid)
			)
			(fill no)
			(layer "B.Fab")
		)
		(fp_text user "Author: Antmicro"
			(at -1.93 -5 0)
			(layer "B.Fab")
			(effects
				(font
					(size 0.7 0.7)
					(thickness 0.15)
				)
				(justify right top mirror)
			)
		)
		(fp_text user "License: Apache-2.0"
			(at -1.93 -6.199 0)
			(layer "B.Fab")
			(effects
				(font
					(size 0.7 0.7)
					(thickness 0.15)
				)
				(justify right top mirror)
			)
		)
		(fp_text user "${REFERENCE}"
			(at -1.93 -3.8 0)
			(layer "B.Fab")
			(effects
				(font
					(size 0.7 0.7)
					(thickness 0.15)
				)
				(justify right top mirror)
			)
		)
		(pad "1" smd rect
			(at -1.301 0.947 90)
			(size 0.7 1.2)
			(layers "B.Cu" "B.Mask" "B.Paste")
			(net 115 "/USB Hub/USBC4_VBUS")
			(pinfunction "OUT")
			(pintype "power_out")
		)
		(pad "2" smd rect
			(at -1.300999 -0.004 90)
			(size 0.7 1.2)
			(layers "B.Cu" "B.Mask" "B.Paste")
			(net 1 "GND")
			(pinfunction "GND")
			(pintype "power_in")
		)
		(pad "3" smd rect
			(at -1.301 -0.954 90)
			(size 0.7 1.2)
			(layers "B.Cu" "B.Mask" "B.Paste")
			(net 914 "/USB Hub/PRT_CTL1")
			(pinfunction "FLG")
			(pintype "output")
		)
		(pad "4" smd rect
			(at 1.299 -0.954 90)
			(size 0.7 1.2)
			(layers "B.Cu" "B.Mask" "B.Paste")
			(net 914 "/USB Hub/PRT_CTL1")
			(pinfunction "EN")
			(pintype "input")
		)
		(pad "5" smd rect
			(at 1.299 -0.004 90)
			(size 0.7 1.2)
			(layers "B.Cu" "B.Mask" "B.Paste")
			(net 1015 "/USB Hub/USBC4_ISET")
			(pinfunction "ISET")
			(pintype "passive")
		)
		(pad "6" smd rect
			(at 1.299 0.947 90)
			(size 0.7 1.2)
			(layers "B.Cu" "B.Mask" "B.Paste")
			(net 5 "+5V")
			(pinfunction "IN")
			(pintype "power_in")
		)
	)
)
